(kicad_pcb
	(version 20260206)
	(generator "pcbnew")
	(generator_version "10.0")
	(general
		(thickness 1.6)
		(legacy_teardrops no)
	)
	(paper "A4")
	(title_block
		(title "03242023_DA0F0TMBIJ0_F0T_Motherboard_J_brd_V01_OCP.brd")
		(comment 1 "Grand Teton / footprints 2163-2169 of 6105")
	)
	(layers
		(0 "F.Cu" signal "TOP")
		(4 "In1.Cu" signal "GND")
		(6 "In2.Cu" signal "IN1")
		(8 "In3.Cu" signal "GND1")
		(10 "In4.Cu" signal "IN2")
		(12 "In5.Cu" signal "GND2")
		(14 "In6.Cu" signal "IN3")
		(16 "In7.Cu" signal "GND3")
		(18 "In8.Cu" signal "VCC")
		(20 "In9.Cu" signal "VCC1")
		(22 "In10.Cu" signal "GND4")
		(24 "In11.Cu" signal "IN4")
		(26 "In12.Cu" signal "GND5")
		(28 "In13.Cu" signal "IN5")
		(30 "In14.Cu" signal "GND6")
		(32 "In15.Cu" signal "IN6")
		(34 "In16.Cu" signal "GND7")
		(2 "B.Cu" signal "BOTTOM")
		(9 "F.Adhes" user "F.Adhesive")
		(11 "B.Adhes" user "B.Adhesive")
		(13 "F.Paste" user "Package Geometry/Pastemask Top")
		(15 "B.Paste" user "Package Geometry/Pastemask Bottom")
		(5 "F.SilkS" user "Ref Des/Silkscreen Top")
		(7 "B.SilkS" user "Ref Des/Silkscreen Bottom")
		(1 "F.Mask" user "Board Geometry/Soldermask Top")
		(3 "B.Mask" user "Board Geometry/Soldermask Bottom")
		(17 "Dwgs.User" user "User.Drawings")
		(19 "Cmts.User" user "User.Comments")
		(21 "Eco1.User" user "User.Eco1")
		(23 "Eco2.User" user "User.Eco2")
		(25 "Edge.Cuts" user "Board Geometry/Outline")
		(27 "Margin" user)
		(31 "F.CrtYd" user "Package Geometry/Place Bound Top")
		(29 "B.CrtYd" user "Package Geometry/Place Bound Bottom")
		(35 "F.Fab" user "Ref Des/Assembly Top")
		(33 "B.Fab" user "Ref Des/Assembly Bottom")
	)
	(footprint ""
		(layer "F.Cu")
		(at 424.511724 -149.239224 -90)
		(property "Reference" "PC180"
			(at 0 0 270)
			(layer "F.SilkS")
			(hide yes)
			(effects
				(font
					(size 1.27 1.27)
				)
			)
		)
		(property "Value" ""
			(at 0 0 270)
			(layer "F.Fab")
			(effects
				(font
					(size 1.27 1.27)
				)
			)
		)
		(duplicate_pad_numbers_are_jumpers no)
		(fp_line
			(start -1.524 0.762)
			(end -1.524 -0.762)
			(stroke
				(width 0.1524)
				(type default)
			)
			(layer "F.SilkS")
		)
		(fp_line
			(start 1.524 0.762)
			(end -1.524 0.762)
			(stroke
				(width 0.1524)
				(type default)
			)
			(layer "F.SilkS")
		)
		(fp_line
			(start -1.524 -0.762)
			(end 1.524 -0.762)
			(stroke
				(width 0.1524)
				(type default)
			)
			(layer "F.SilkS")
		)
		(fp_line
			(start 1.524 -0.762)
			(end 1.524 0.762)
			(stroke
				(width 0.1524)
				(type default)
			)
			(layer "F.SilkS")
		)
		(fp_line
			(start -1.1049 0.724916)
			(end 1.1049 0.724916)
			(stroke
				(width 0.1)
				(type default)
			)
			(layer "F.Fab")
		)
		(fp_line
			(start 1.1049 0.724916)
			(end 1.1049 -0.724916)
			(stroke
				(width 0.1)
				(type default)
			)
			(layer "F.Fab")
		)
		(fp_line
			(start -1.1049 -0.724916)
			(end -1.1049 0.724916)
			(stroke
				(width 0.1)
				(type default)
			)
			(layer "F.Fab")
		)
		(fp_line
			(start 1.1049 -0.724916)
			(end -1.1049 -0.724916)
			(stroke
				(width 0.1)
				(type default)
			)
			(layer "F.Fab")
		)
		(pad "1" smd rect
			(at -0.889 0 90)
			(size 1.016 1.27)
			(layers "F.Cu" "F.Mask" "F.Paste")
			(net "SW_P12V_PVCCINFAON_CPU0_FLT")
		)
		(pad "2" smd rect
			(at 0.889 0 90)
			(size 1.016 1.27)
			(layers "F.Cu" "F.Mask" "F.Paste")
			(net "GND")
		)
	)
	(footprint ""
		(layer "F.Cu")
		(at 191.295782 -29.283152 180)
		(property "Reference" "PC2236"
			(at 0 0 180)
			(layer "F.SilkS")
			(hide yes)
			(effects
				(font
					(size 1.27 1.27)
				)
			)
		)
		(property "Value" ""
			(at 0 0 180)
			(layer "F.Fab")
			(effects
				(font
					(size 1.27 1.27)
				)
			)
		)
		(duplicate_pad_numbers_are_jumpers no)
		(fp_line
			(start 0.7874 0.4064)
			(end -0.7874 0.4064)
			(stroke
				(width 0.1524)
				(type default)
			)
			(layer "F.SilkS")
		)
		(fp_line
			(start 0.7874 -0.4064)
			(end 0.7874 0.4064)
			(stroke
				(width 0.1524)
				(type default)
			)
			(layer "F.SilkS")
		)
		(fp_line
			(start -0.7874 0.4064)
			(end -0.7874 -0.4064)
			(stroke
				(width 0.1524)
				(type default)
			)
			(layer "F.SilkS")
		)
		(fp_line
			(start -0.7874 -0.4064)
			(end 0.7874 -0.4064)
			(stroke
				(width 0.1524)
				(type default)
			)
			(layer "F.SilkS")
		)
		(fp_line
			(start 0.67945 0.3048)
			(end 0.120396 0.3048)
			(stroke
				(width 0.1)
				(type default)
			)
			(layer "F.Fab")
		)
		(fp_line
			(start 0.67945 -0.3048)
			(end 0.67945 0.3048)
			(stroke
				(width 0.1)
				(type default)
			)
			(layer "F.Fab")
		)
		(fp_line
			(start 0.12065 -0.2794)
			(end 0.12065 -0.3048)
			(stroke
				(width 0.1)
				(type default)
			)
			(layer "F.Fab")
		)
		(fp_line
			(start 0.12065 -0.3048)
			(end 0.67945 -0.3048)
			(stroke
				(width 0.1)
				(type default)
			)
			(layer "F.Fab")
		)
		(fp_line
			(start 0.120396 0.3048)
			(end 0.120396 0.2794)
			(stroke
				(width 0.1)
				(type default)
			)
			(layer "F.Fab")
		)
		(fp_line
			(start 0.120396 0.2794)
			(end -0.12065 0.2794)
			(stroke
				(width 0.1)
				(type default)
			)
			(layer "F.Fab")
		)
		(fp_line
			(start -0.12065 0.3048)
			(end -0.67945 0.3048)
			(stroke
				(width 0.1)
				(type default)
			)
			(layer "F.Fab")
		)
		(fp_line
			(start -0.12065 0.2794)
			(end -0.12065 0.3048)
			(stroke
				(width 0.1)
				(type default)
			)
			(layer "F.Fab")
		)
		(fp_line
			(start -0.12065 -0.2794)
			(end 0.12065 -0.2794)
			(stroke
				(width 0.1)
				(type default)
			)
			(layer "F.Fab")
		)
		(fp_line
			(start -0.12065 -0.305054)
			(end -0.12065 -0.2794)
			(stroke
				(width 0.1)
				(type default)
			)
			(layer "F.Fab")
		)
		(fp_line
			(start -0.67945 0.3048)
			(end -0.67945 -0.305054)
			(stroke
				(width 0.1)
				(type default)
			)
			(layer "F.Fab")
		)
		(fp_line
			(start -0.67945 -0.305054)
			(end -0.12065 -0.305054)
			(stroke
				(width 0.1)
				(type default)
			)
			(layer "F.Fab")
		)
		(pad "1" smd circle
			(at -0.40005 0 180)
			(size 0 0)
			(layers "F.Cu" "F.Mask" "F.Paste")
			(net "P12V_SCM_R")
		)
		(pad "2" smd circle
			(at 0.40005 0 180)
			(size 0 0)
			(layers "F.Cu" "F.Mask" "F.Paste")
			(net "P12V_SCM_GATE")
		)
	)
	(footprint ""
		(layer "F.Cu")
		(at 260.593332 -92.497656 90)
		(property "Reference" "R3639"
			(at 0 0 90)
			(layer "F.SilkS")
			(hide yes)
			(effects
				(font
					(size 1.27 1.27)
				)
			)
		)
		(property "Value" ""
			(at 0 0 90)
			(layer "F.Fab")
			(effects
				(font
					(size 1.27 1.27)
				)
			)
		)
		(duplicate_pad_numbers_are_jumpers no)
		(fp_line
			(start 0.7874 -0.4064)
			(end 0.7874 0.4064)
			(stroke
				(width 0.1524)
				(type default)
			)
			(layer "F.SilkS")
		)
		(fp_line
			(start -0.7874 -0.4064)
			(end 0.7874 -0.4064)
			(stroke
				(width 0.1524)
				(type default)
			)
			(layer "F.SilkS")
		)
		(fp_line
			(start 0.7874 0.4064)
			(end -0.7874 0.4064)
			(stroke
				(width 0.1524)
				(type default)
			)
			(layer "F.SilkS")
		)
		(fp_line
			(start -0.7874 0.4064)
			(end -0.7874 -0.4064)
			(stroke
				(width 0.1524)
				(type default)
			)
			(layer "F.SilkS")
		)
		(fp_line
			(start -0.12065 -0.305054)
			(end -0.12065 -0.2794)
			(stroke
				(width 0.1)
				(type default)
			)
			(layer "F.Fab")
		)
		(fp_line
			(start -0.67945 -0.305054)
			(end -0.12065 -0.305054)
			(stroke
				(width 0.1)
				(type default)
			)
			(layer "F.Fab")
		)
		(fp_line
			(start 0.67945 -0.3048)
			(end 0.67945 0.3048)
			(stroke
				(width 0.1)
				(type default)
			)
			(layer "F.Fab")
		)
		(fp_line
			(start 0.12065 -0.3048)
			(end 0.67945 -0.3048)
			(stroke
				(width 0.1)
				(type default)
			)
			(layer "F.Fab")
		)
		(fp_line
			(start 0.12065 -0.2794)
			(end 0.12065 -0.3048)
			(stroke
				(width 0.1)
				(type default)
			)
			(layer "F.Fab")
		)
		(fp_line
			(start -0.12065 -0.2794)
			(end 0.12065 -0.2794)
			(stroke
				(width 0.1)
				(type default)
			)
			(layer "F.Fab")
		)
		(fp_line
			(start 0.120396 0.2794)
			(end -0.12065 0.2794)
			(stroke
				(width 0.1)
				(type default)
			)
			(layer "F.Fab")
		)
		(fp_line
			(start -0.12065 0.2794)
			(end -0.12065 0.3048)
			(stroke
				(width 0.1)
				(type default)
			)
			(layer "F.Fab")
		)
		(fp_line
			(start 0.67945 0.3048)
			(end 0.120396 0.3048)
			(stroke
				(width 0.1)
				(type default)
			)
			(layer "F.Fab")
		)
		(fp_line
			(start 0.120396 0.3048)
			(end 0.120396 0.2794)
			(stroke
				(width 0.1)
				(type default)
			)
			(layer "F.Fab")
		)
		(fp_line
			(start -0.12065 0.3048)
			(end -0.67945 0.3048)
			(stroke
				(width 0.1)
				(type default)
			)
			(layer "F.Fab")
		)
		(fp_line
			(start -0.67945 0.3048)
			(end -0.67945 -0.305054)
			(stroke
				(width 0.1)
				(type default)
			)
			(layer "F.Fab")
		)
		(pad "1" smd circle
			(at -0.40005 0 90)
			(size 0 0)
			(layers "F.Cu" "F.Mask" "F.Paste")
			(net "P3V3_AUX")
		)
		(pad "2" smd circle
			(at 0.40005 0 90)
			(size 0 0)
			(layers "F.Cu" "F.Mask" "F.Paste")
			(net "CK440Q_OE_2")
		)
	)
	(footprint ""
		(layer "F.Cu")
		(at 277.859744 -407.401776 -90)
		(property "Reference" "PR3"
			(at 0 0 270)
			(layer "F.SilkS")
			(hide yes)
			(effects
				(font
					(size 1.27 1.27)
				)
			)
		)
		(property "Value" ""
			(at 0 0 270)
			(layer "F.Fab")
			(effects
				(font
					(size 1.27 1.27)
				)
			)
		)
		(duplicate_pad_numbers_are_jumpers no)
		(fp_line
			(start -4.0386 1.7526)
			(end -4.0386 -1.7526)
			(stroke
				(width 0.1524)
				(type default)
			)
			(layer "F.SilkS")
		)
		(fp_line
			(start 4.0386 1.7526)
			(end -4.0386 1.7526)
			(stroke
				(width 0.1524)
				(type default)
			)
			(layer "F.SilkS")
		)
		(fp_line
			(start -4.0386 -1.7526)
			(end 4.0386 -1.7526)
			(stroke
				(width 0.1524)
				(type default)
			)
			(layer "F.SilkS")
		)
		(fp_line
			(start 4.0386 -1.7526)
			(end 4.0386 1.7526)
			(stroke
				(width 0.1524)
				(type default)
			)
			(layer "F.SilkS")
		)
		(fp_line
			(start -4.0386 1.7526)
			(end -4.0386 -1.7526)
			(stroke
				(width 0.1)
				(type default)
			)
			(layer "F.Fab")
		)
		(fp_line
			(start 4.0386 1.7526)
			(end -4.0386 1.7526)
			(stroke
				(width 0.1)
				(type default)
			)
			(layer "F.Fab")
		)
		(fp_line
			(start -4.0386 -1.7526)
			(end 4.0386 -1.7526)
			(stroke
				(width 0.1)
				(type default)
			)
			(layer "F.Fab")
		)
		(fp_line
			(start 4.0386 -1.7526)
			(end 4.0386 1.7526)
			(stroke
				(width 0.1)
				(type default)
			)
			(layer "F.Fab")
		)
		(pad "1" smd circle
			(at -3.700018 0 180)
			(size 0 0)
			(layers "F.Cu" "F.Mask" "F.Paste")
			(net "P12V_PSU")
		)
		(pad "2" smd circle
			(at 3.700018 0)
			(size 0 0)
			(layers "F.Cu" "F.Mask" "F.Paste")
			(net "P12V_MAIN_R_0")
		)
		(pad "3" smd rect
			(at -2.70002 0)
			(size 0.4064 1.1176)
			(layers "F.Cu" "F.Mask" "F.Paste")
			(net "P12V_HSC_SENSE1_P")
		)
		(pad "4" smd rect
			(at 2.70002 0)
			(size 0.4064 1.1176)
			(layers "F.Cu" "F.Mask" "F.Paste")
			(net "P12V_HSC_SENSE1_N")
		)
	)
	(footprint ""
		(layer "F.Cu")
		(at 463.90687 -68.519802 90)
		(property "Reference" "PC3"
			(at 0 0 90)
			(layer "F.SilkS")
			(hide yes)
			(effects
				(font
					(size 1.27 1.27)
				)
			)
		)
		(property "Value" ""
			(at 0 0 90)
			(layer "F.Fab")
			(effects
				(font
					(size 1.27 1.27)
				)
			)
		)
		(duplicate_pad_numbers_are_jumpers no)
		(fp_line
			(start -3.400044 1.249934)
			(end 3.400044 1.249934)
			(stroke
				(width 0.1524)
				(type default)
			)
			(layer "F.SilkS")
		)
		(fp_circle
			(center 0 1.249934)
			(end 0 4.649978)
			(stroke
				(width 0.1524)
				(type default)
			)
			(fill no)
			(layer "F.SilkS")
		)
		(fp_poly
			(pts
				(arc
					(start -3.400044 1.249934)
					(mid 0 4.649978)
					(end 3.400044 1.249934)
				)
			)
			(stroke
				(width 0)
				(type default)
			)
			(fill yes)
			(layer "F.SilkS")
		)
		(fp_circle
			(center 0 1.249934)
			(end 0 4.649978)
			(stroke
				(width 0.1)
				(type default)
			)
			(fill no)
			(layer "F.Fab")
		)
		(pad "1" thru_hole rect
			(at 0 0 90)
			(size 1.524 1.524)
			(drill 1.016)
			(layers "*.Cu" "*.Mask")
			(remove_unused_layers no)
			(net "SW_P3V3_AUX_FLT")
			(clearance 0)
			(padstack
				(mode front_inner_back)
				(layer "Inner"
					(shape circle)
					(size 1.524 1.524)
					(clearance 0)
				)
				(layer "B.Cu"
					(shape rect)
					(size 1.524 1.524)
					(clearance 0)
				)
			)
		)
		(pad "2" thru_hole circle
			(at 0 2.500122 90)
			(size 1.524 1.524)
			(drill 1.016)
			(layers "*.Cu" "*.Mask")
			(remove_unused_layers no)
			(net "GND")
			(clearance 0)
		)
	)
	(footprint ""
		(layer "F.Cu")
		(at 103.306372 -362.602526)
		(property "Reference" "R2520"
			(at 0 0 0)
			(layer "F.SilkS")
			(hide yes)
			(effects
				(font
					(size 1.27 1.27)
				)
			)
		)
		(property "Value" ""
			(at 0 0 0)
			(layer "F.Fab")
			(effects
				(font
					(size 1.27 1.27)
				)
			)
		)
		(duplicate_pad_numbers_are_jumpers no)
		(fp_line
			(start -0.7874 -0.4064)
			(end 0.7874 -0.4064)
			(stroke
				(width 0.1524)
				(type default)
			)
			(layer "F.SilkS")
		)
		(fp_line
			(start -0.7874 0.4064)
			(end -0.7874 -0.4064)
			(stroke
				(width 0.1524)
				(type default)
			)
			(layer "F.SilkS")
		)
		(fp_line
			(start 0.7874 -0.4064)
			(end 0.7874 0.4064)
			(stroke
				(width 0.1524)
				(type default)
			)
			(layer "F.SilkS")
		)
		(fp_line
			(start 0.7874 0.4064)
			(end -0.7874 0.4064)
			(stroke
				(width 0.1524)
				(type default)
			)
			(layer "F.SilkS")
		)
		(fp_line
			(start -0.67945 -0.305054)
			(end -0.12065 -0.305054)
			(stroke
				(width 0.1)
				(type default)
			)
			(layer "F.Fab")
		)
		(fp_line
			(start -0.67945 0.3048)
			(end -0.67945 -0.305054)
			(stroke
				(width 0.1)
				(type default)
			)
			(layer "F.Fab")
		)
		(fp_line
			(start -0.12065 -0.305054)
			(end -0.12065 -0.2794)
			(stroke
				(width 0.1)
				(type default)
			)
			(layer "F.Fab")
		)
		(fp_line
			(start -0.12065 -0.2794)
			(end 0.12065 -0.2794)
			(stroke
				(width 0.1)
				(type default)
			)
			(layer "F.Fab")
		)
		(fp_line
			(start -0.12065 0.2794)
			(end -0.12065 0.3048)
			(stroke
				(width 0.1)
				(type default)
			)
			(layer "F.Fab")
		)
		(fp_line
			(start -0.12065 0.3048)
			(end -0.67945 0.3048)
			(stroke
				(width 0.1)
				(type default)
			)
			(layer "F.Fab")
		)
		(fp_line
			(start 0.120396 0.2794)
			(end -0.12065 0.2794)
			(stroke
				(width 0.1)
				(type default)
			)
			(layer "F.Fab")
		)
		(fp_line
			(start 0.120396 0.3048)
			(end 0.120396 0.2794)
			(stroke
				(width 0.1)
				(type default)
			)
			(layer "F.Fab")
		)
		(fp_line
			(start 0.12065 -0.3048)
			(end 0.67945 -0.3048)
			(stroke
				(width 0.1)
				(type default)
			)
			(layer "F.Fab")
		)
		(fp_line
			(start 0.12065 -0.2794)
			(end 0.12065 -0.3048)
			(stroke
				(width 0.1)
				(type default)
			)
			(layer "F.Fab")
		)
		(fp_line
			(start 0.67945 -0.3048)
			(end 0.67945 0.3048)
			(stroke
				(width 0.1)
				(type default)
			)
			(layer "F.Fab")
		)
		(fp_line
			(start 0.67945 0.3048)
			(end 0.120396 0.3048)
			(stroke
				(width 0.1)
				(type default)
			)
			(layer "F.Fab")
		)
		(pad "1" smd circle
			(at -0.40005 0)
			(size 0 0)
			(layers "F.Cu" "F.Mask" "F.Paste")
			(net "SMB_VR_3V3AUX_SCL_R3")
		)
		(pad "2" smd circle
			(at 0.40005 0)
			(size 0 0)
			(layers "F.Cu" "F.Mask" "F.Paste")
			(net "SMB_CLK_PVCCIN_CPU1")
		)
	)
	(footprint ""
		(layer "F.Cu")
		(at 104.349804 -245.634256 -90)
		(property "Reference" "C423"
			(at 0 0 270)
			(layer "F.SilkS")
			(hide yes)
			(effects
				(font
					(size 1.27 1.27)
				)
			)
		)
		(property "Value" ""
			(at 0 0 270)
			(layer "F.Fab")
			(effects
				(font
					(size 1.27 1.27)
				)
			)
		)
		(duplicate_pad_numbers_are_jumpers no)
		(fp_line
			(start -0.7874 0.4064)
			(end -0.7874 -0.4064)
			(stroke
				(width 0.1524)
				(type default)
			)
			(layer "F.SilkS")
		)
		(fp_line
			(start 0.7874 0.4064)
			(end -0.7874 0.4064)
			(stroke
				(width 0.1524)
				(type default)
			)
			(layer "F.SilkS")
		)
		(fp_line
			(start -0.7874 -0.4064)
			(end 0.7874 -0.4064)
			(stroke
				(width 0.1524)
				(type default)
			)
			(layer "F.SilkS")
		)
		(fp_line
			(start 0.7874 -0.4064)
			(end 0.7874 0.4064)
			(stroke
				(width 0.1524)
				(type default)
			)
			(layer "F.SilkS")
		)
		(fp_line
			(start -0.67945 0.3048)
			(end -0.67945 -0.305054)
			(stroke
				(width 0.1)
				(type default)
			)
			(layer "F.Fab")
		)
		(fp_line
			(start -0.12065 0.3048)
			(end -0.67945 0.3048)
			(stroke
				(width 0.1)
				(type default)
			)
			(layer "F.Fab")
		)
		(fp_line
			(start 0.120396 0.3048)
			(end 0.120396 0.2794)
			(stroke
				(width 0.1)
				(type default)
			)
			(layer "F.Fab")
		)
		(fp_line
			(start 0.67945 0.3048)
			(end 0.120396 0.3048)
			(stroke
				(width 0.1)
				(type default)
			)
			(layer "F.Fab")
		)
		(fp_line
			(start -0.12065 0.2794)
			(end -0.12065 0.3048)
			(stroke
				(width 0.1)
				(type default)
			)
			(layer "F.Fab")
		)
		(fp_line
			(start 0.120396 0.2794)
			(end -0.12065 0.2794)
			(stroke
				(width 0.1)
				(type default)
			)
			(layer "F.Fab")
		)
		(fp_line
			(start -0.12065 -0.2794)
			(end 0.12065 -0.2794)
			(stroke
				(width 0.1)
				(type default)
			)
			(layer "F.Fab")
		)
		(fp_line
			(start 0.12065 -0.2794)
			(end 0.12065 -0.3048)
			(stroke
				(width 0.1)
				(type default)
			)
			(layer "F.Fab")
		)
		(fp_line
			(start 0.12065 -0.3048)
			(end 0.67945 -0.3048)
			(stroke
				(width 0.1)
				(type default)
			)
			(layer "F.Fab")
		)
		(fp_line
			(start 0.67945 -0.3048)
			(end 0.67945 0.3048)
			(stroke
				(width 0.1)
				(type default)
			)
			(layer "F.Fab")
		)
		(fp_line
			(start -0.67945 -0.305054)
			(end -0.12065 -0.305054)
			(stroke
				(width 0.1)
				(type default)
			)
			(layer "F.Fab")
		)
		(fp_line
			(start -0.12065 -0.305054)
			(end -0.12065 -0.2794)
			(stroke
				(width 0.1)
				(type default)
			)
			(layer "F.Fab")
		)
		(pad "1" smd circle
			(at -0.40005 0 270)
			(size 0 0)
			(layers "F.Cu" "F.Mask" "F.Paste")
			(net "PVCCD_HV_CPU1")
		)
		(pad "2" smd circle
			(at 0.40005 0 270)
			(size 0 0)
			(layers "F.Cu" "F.Mask" "F.Paste")
			(net "GND")
		)
	)
)
